(kicad_pcb
	(version 20260206)
	(generator "pcbnew")
	(generator_version "10.0")
	(general
		(thickness 1.6)
		(legacy_teardrops no)
	)
	(paper "A4")
	(title_block
		(title "03242023_DA0F0TMBIJ0_F0T_Motherboard_J_brd_V01_OCP.brd")
		(comment 1 "Grand Teton / footprints 5806-5811 of 6105")
	)
	(layers
		(0 "F.Cu" signal "TOP")
		(4 "In1.Cu" signal "GND")
		(6 "In2.Cu" signal "IN1")
		(8 "In3.Cu" signal "GND1")
		(10 "In4.Cu" signal "IN2")
		(12 "In5.Cu" signal "GND2")
		(14 "In6.Cu" signal "IN3")
		(16 "In7.Cu" signal "GND3")
		(18 "In8.Cu" signal "VCC")
		(20 "In9.Cu" signal "VCC1")
		(22 "In10.Cu" signal "GND4")
		(24 "In11.Cu" signal "IN4")
		(26 "In12.Cu" signal "GND5")
		(28 "In13.Cu" signal "IN5")
		(30 "In14.Cu" signal "GND6")
		(32 "In15.Cu" signal "IN6")
		(34 "In16.Cu" signal "GND7")
		(2 "B.Cu" signal "BOTTOM")
		(9 "F.Adhes" user "F.Adhesive")
		(11 "B.Adhes" user "B.Adhesive")
		(13 "F.Paste" user "Package Geometry/Pastemask Top")
		(15 "B.Paste" user "Package Geometry/Pastemask Bottom")
		(5 "F.SilkS" user "Ref Des/Silkscreen Top")
		(7 "B.SilkS" user "Ref Des/Silkscreen Bottom")
		(1 "F.Mask" user "Board Geometry/Soldermask Top")
		(3 "B.Mask" user "Board Geometry/Soldermask Bottom")
		(17 "Dwgs.User" user "User.Drawings")
		(19 "Cmts.User" user "User.Comments")
		(21 "Eco1.User" user "User.Eco1")
		(23 "Eco2.User" user "User.Eco2")
		(25 "Edge.Cuts" user "Board Geometry/Outline")
		(27 "Margin" user)
		(31 "F.CrtYd" user "Package Geometry/Place Bound Top")
		(29 "B.CrtYd" user "Package Geometry/Place Bound Bottom")
		(35 "F.Fab" user "Ref Des/Assembly Top")
		(33 "B.Fab" user "Ref Des/Assembly Bottom")
	)
	(footprint ""
		(layer "B.Cu")
		(at 198.086472 -318.332358)
		(property "Reference" "R75"
			(at 0 0 0)
			(layer "B.SilkS")
			(hide yes)
			(effects
				(font
					(size 1.27 1.27)
				)
				(justify mirror)
			)
		)
		(property "Value" ""
			(at 0 0 0)
			(layer "B.Fab")
			(effects
				(font
					(size 1.27 1.27)
				)
				(justify mirror)
			)
		)
		(duplicate_pad_numbers_are_jumpers no)
		(fp_line
			(start -0.7874 -0.4064)
			(end -0.7874 0.4064)
			(stroke
				(width 0.1524)
				(type default)
			)
			(layer "B.SilkS")
		)
		(fp_line
			(start -0.7874 0.4064)
			(end 0.7874 0.4064)
			(stroke
				(width 0.1524)
				(type default)
			)
			(layer "B.SilkS")
		)
		(fp_line
			(start 0.7874 -0.4064)
			(end -0.7874 -0.4064)
			(stroke
				(width 0.1524)
				(type default)
			)
			(layer "B.SilkS")
		)
		(fp_line
			(start 0.7874 0.4064)
			(end 0.7874 -0.4064)
			(stroke
				(width 0.1524)
				(type default)
			)
			(layer "B.SilkS")
		)
		(fp_line
			(start -0.67945 -0.3048)
			(end -0.67945 0.3048)
			(stroke
				(width 0.1)
				(type default)
			)
			(layer "B.Fab")
		)
		(fp_line
			(start -0.67945 0.3048)
			(end -0.120396 0.3048)
			(stroke
				(width 0.1)
				(type default)
			)
			(layer "B.Fab")
		)
		(fp_line
			(start -0.12065 -0.3048)
			(end -0.67945 -0.3048)
			(stroke
				(width 0.1)
				(type default)
			)
			(layer "B.Fab")
		)
		(fp_line
			(start -0.12065 -0.2794)
			(end -0.12065 -0.3048)
			(stroke
				(width 0.1)
				(type default)
			)
			(layer "B.Fab")
		)
		(fp_line
			(start -0.120396 0.2794)
			(end 0.12065 0.2794)
			(stroke
				(width 0.1)
				(type default)
			)
			(layer "B.Fab")
		)
		(fp_line
			(start -0.120396 0.3048)
			(end -0.120396 0.2794)
			(stroke
				(width 0.1)
				(type default)
			)
			(layer "B.Fab")
		)
		(fp_line
			(start 0.12065 -0.305054)
			(end 0.12065 -0.2794)
			(stroke
				(width 0.1)
				(type default)
			)
			(layer "B.Fab")
		)
		(fp_line
			(start 0.12065 -0.2794)
			(end -0.12065 -0.2794)
			(stroke
				(width 0.1)
				(type default)
			)
			(layer "B.Fab")
		)
		(fp_line
			(start 0.12065 0.2794)
			(end 0.12065 0.3048)
			(stroke
				(width 0.1)
				(type default)
			)
			(layer "B.Fab")
		)
		(fp_line
			(start 0.12065 0.3048)
			(end 0.67945 0.3048)
			(stroke
				(width 0.1)
				(type default)
			)
			(layer "B.Fab")
		)
		(fp_line
			(start 0.67945 -0.305054)
			(end 0.12065 -0.305054)
			(stroke
				(width 0.1)
				(type default)
			)
			(layer "B.Fab")
		)
		(fp_line
			(start 0.67945 0.3048)
			(end 0.67945 -0.305054)
			(stroke
				(width 0.1)
				(type default)
			)
			(layer "B.Fab")
		)
		(pad "1" smd circle
			(at 0.40005 0 180)
			(size 0 0)
			(layers "B.Cu" "B.Mask" "B.Paste")
			(net "PD_CHG_CPU1_DIMM1_SAA")
		)
		(pad "2" smd circle
			(at -0.40005 0 180)
			(size 0 0)
			(layers "B.Cu" "B.Mask" "B.Paste")
			(net "GND")
		)
	)
	(footprint ""
		(layer "B.Cu")
		(at 65.023746 -321.554856 -90)
		(property "Reference" "C54"
			(at 0 0 90)
			(layer "B.SilkS")
			(hide yes)
			(effects
				(font
					(size 1.27 1.27)
				)
				(justify mirror)
			)
		)
		(property "Value" ""
			(at 0 0 90)
			(layer "B.Fab")
			(effects
				(font
					(size 1.27 1.27)
				)
				(justify mirror)
			)
		)
		(duplicate_pad_numbers_are_jumpers no)
		(fp_line
			(start -1.524 0.762)
			(end 1.524 0.762)
			(stroke
				(width 0.1524)
				(type default)
			)
			(layer "B.SilkS")
		)
		(fp_line
			(start 1.524 0.762)
			(end 1.524 -0.762)
			(stroke
				(width 0.1524)
				(type default)
			)
			(layer "B.SilkS")
		)
		(fp_line
			(start -1.524 -0.762)
			(end -1.524 0.762)
			(stroke
				(width 0.1524)
				(type default)
			)
			(layer "B.SilkS")
		)
		(fp_line
			(start 1.524 -0.762)
			(end -1.524 -0.762)
			(stroke
				(width 0.1524)
				(type default)
			)
			(layer "B.SilkS")
		)
		(fp_line
			(start -1.1049 0.724916)
			(end -1.1049 -0.724916)
			(stroke
				(width 0.1)
				(type default)
			)
			(layer "B.Fab")
		)
		(fp_line
			(start 1.1049 0.724916)
			(end -1.1049 0.724916)
			(stroke
				(width 0.1)
				(type default)
			)
			(layer "B.Fab")
		)
		(fp_line
			(start -1.1049 -0.724916)
			(end 1.1049 -0.724916)
			(stroke
				(width 0.1)
				(type default)
			)
			(layer "B.Fab")
		)
		(fp_line
			(start 1.1049 -0.724916)
			(end 1.1049 0.724916)
			(stroke
				(width 0.1)
				(type default)
			)
			(layer "B.Fab")
		)
		(pad "1" smd rect
			(at 0.889 0 270)
			(size 1.016 1.27)
			(layers "B.Cu" "B.Mask" "B.Paste")
			(net "P12V_S3_AUX_CPU1_NVDIMM")
		)
		(pad "2" smd rect
			(at -0.889 0 270)
			(size 1.016 1.27)
			(layers "B.Cu" "B.Mask" "B.Paste")
			(net "GND")
		)
	)
	(footprint ""
		(layer "B.Cu")
		(at 191.992758 -69.443346)
		(property "Reference" "R3213"
			(at 0 0 0)
			(layer "B.SilkS")
			(hide yes)
			(effects
				(font
					(size 1.27 1.27)
				)
				(justify mirror)
			)
		)
		(property "Value" ""
			(at 0 0 0)
			(layer "B.Fab")
			(effects
				(font
					(size 1.27 1.27)
				)
				(justify mirror)
			)
		)
		(duplicate_pad_numbers_are_jumpers no)
		(fp_line
			(start -0.7874 -0.4064)
			(end -0.7874 0.4064)
			(stroke
				(width 0.1524)
				(type default)
			)
			(layer "B.SilkS")
		)
		(fp_line
			(start -0.7874 0.4064)
			(end 0.7874 0.4064)
			(stroke
				(width 0.1524)
				(type default)
			)
			(layer "B.SilkS")
		)
		(fp_line
			(start 0.7874 -0.4064)
			(end -0.7874 -0.4064)
			(stroke
				(width 0.1524)
				(type default)
			)
			(layer "B.SilkS")
		)
		(fp_line
			(start 0.7874 0.4064)
			(end 0.7874 -0.4064)
			(stroke
				(width 0.1524)
				(type default)
			)
			(layer "B.SilkS")
		)
		(fp_line
			(start -0.67945 -0.3048)
			(end -0.67945 0.3048)
			(stroke
				(width 0.1)
				(type default)
			)
			(layer "B.Fab")
		)
		(fp_line
			(start -0.67945 0.3048)
			(end -0.120396 0.3048)
			(stroke
				(width 0.1)
				(type default)
			)
			(layer "B.Fab")
		)
		(fp_line
			(start -0.12065 -0.3048)
			(end -0.67945 -0.3048)
			(stroke
				(width 0.1)
				(type default)
			)
			(layer "B.Fab")
		)
		(fp_line
			(start -0.12065 -0.2794)
			(end -0.12065 -0.3048)
			(stroke
				(width 0.1)
				(type default)
			)
			(layer "B.Fab")
		)
		(fp_line
			(start -0.120396 0.2794)
			(end 0.12065 0.2794)
			(stroke
				(width 0.1)
				(type default)
			)
			(layer "B.Fab")
		)
		(fp_line
			(start -0.120396 0.3048)
			(end -0.120396 0.2794)
			(stroke
				(width 0.1)
				(type default)
			)
			(layer "B.Fab")
		)
		(fp_line
			(start 0.12065 -0.305054)
			(end 0.12065 -0.2794)
			(stroke
				(width 0.1)
				(type default)
			)
			(layer "B.Fab")
		)
		(fp_line
			(start 0.12065 -0.2794)
			(end -0.12065 -0.2794)
			(stroke
				(width 0.1)
				(type default)
			)
			(layer "B.Fab")
		)
		(fp_line
			(start 0.12065 0.2794)
			(end 0.12065 0.3048)
			(stroke
				(width 0.1)
				(type default)
			)
			(layer "B.Fab")
		)
		(fp_line
			(start 0.12065 0.3048)
			(end 0.67945 0.3048)
			(stroke
				(width 0.1)
				(type default)
			)
			(layer "B.Fab")
		)
		(fp_line
			(start 0.67945 -0.305054)
			(end 0.12065 -0.305054)
			(stroke
				(width 0.1)
				(type default)
			)
			(layer "B.Fab")
		)
		(fp_line
			(start 0.67945 0.3048)
			(end 0.67945 -0.305054)
			(stroke
				(width 0.1)
				(type default)
			)
			(layer "B.Fab")
		)
		(pad "1" smd circle
			(at 0.40005 0 180)
			(size 0 0)
			(layers "B.Cu" "B.Mask" "B.Paste")
			(net "NCSI_BMC_TX_EN_R1")
		)
		(pad "2" smd circle
			(at -0.40005 0 180)
			(size 0 0)
			(layers "B.Cu" "B.Mask" "B.Paste")
			(net "RMII_BMC_OCP_TX_EN")
		)
	)
	(footprint ""
		(layer "B.Cu")
		(at 315.14288 -49.113948 180)
		(property "Reference" "R1262"
			(at 0 0 0)
			(layer "B.SilkS")
			(hide yes)
			(effects
				(font
					(size 1.27 1.27)
				)
				(justify mirror)
			)
		)
		(property "Value" ""
			(at 0 0 0)
			(layer "B.Fab")
			(effects
				(font
					(size 1.27 1.27)
				)
				(justify mirror)
			)
		)
		(duplicate_pad_numbers_are_jumpers no)
		(fp_line
			(start 0.7874 0.4064)
			(end 0.7874 -0.4064)
			(stroke
				(width 0.1524)
				(type default)
			)
			(layer "B.SilkS")
		)
		(fp_line
			(start 0.7874 -0.4064)
			(end -0.7874 -0.4064)
			(stroke
				(width 0.1524)
				(type default)
			)
			(layer "B.SilkS")
		)
		(fp_line
			(start -0.7874 0.4064)
			(end 0.7874 0.4064)
			(stroke
				(width 0.1524)
				(type default)
			)
			(layer "B.SilkS")
		)
		(fp_line
			(start -0.7874 -0.4064)
			(end -0.7874 0.4064)
			(stroke
				(width 0.1524)
				(type default)
			)
			(layer "B.SilkS")
		)
		(fp_line
			(start 0.67945 0.3048)
			(end 0.67945 -0.305054)
			(stroke
				(width 0.1)
				(type default)
			)
			(layer "B.Fab")
		)
		(fp_line
			(start 0.67945 -0.305054)
			(end 0.12065 -0.305054)
			(stroke
				(width 0.1)
				(type default)
			)
			(layer "B.Fab")
		)
		(fp_line
			(start 0.12065 0.3048)
			(end 0.67945 0.3048)
			(stroke
				(width 0.1)
				(type default)
			)
			(layer "B.Fab")
		)
		(fp_line
			(start 0.12065 0.2794)
			(end 0.12065 0.3048)
			(stroke
				(width 0.1)
				(type default)
			)
			(layer "B.Fab")
		)
		(fp_line
			(start 0.12065 -0.2794)
			(end -0.12065 -0.2794)
			(stroke
				(width 0.1)
				(type default)
			)
			(layer "B.Fab")
		)
		(fp_line
			(start 0.12065 -0.305054)
			(end 0.12065 -0.2794)
			(stroke
				(width 0.1)
				(type default)
			)
			(layer "B.Fab")
		)
		(fp_line
			(start -0.120396 0.3048)
			(end -0.120396 0.2794)
			(stroke
				(width 0.1)
				(type default)
			)
			(layer "B.Fab")
		)
		(fp_line
			(start -0.120396 0.2794)
			(end 0.12065 0.2794)
			(stroke
				(width 0.1)
				(type default)
			)
			(layer "B.Fab")
		)
		(fp_line
			(start -0.12065 -0.2794)
			(end -0.12065 -0.3048)
			(stroke
				(width 0.1)
				(type default)
			)
			(layer "B.Fab")
		)
		(fp_line
			(start -0.12065 -0.3048)
			(end -0.67945 -0.3048)
			(stroke
				(width 0.1)
				(type default)
			)
			(layer "B.Fab")
		)
		(fp_line
			(start -0.67945 0.3048)
			(end -0.120396 0.3048)
			(stroke
				(width 0.1)
				(type default)
			)
			(layer "B.Fab")
		)
		(fp_line
			(start -0.67945 -0.3048)
			(end -0.67945 0.3048)
			(stroke
				(width 0.1)
				(type default)
			)
			(layer "B.Fab")
		)
		(pad "1" smd circle
			(at 0.40005 0)
			(size 0 0)
			(layers "B.Cu" "B.Mask" "B.Paste")
			(net "P1V05_PCH_AUX")
		)
		(pad "2" smd circle
			(at -0.40005 0)
			(size 0 0)
			(layers "B.Cu" "B.Mask" "B.Paste")
			(net "H_CPU_ERR2_PCH_R_N")
		)
	)
	(footprint ""
		(layer "B.Cu")
		(at 404.006812 -53.727604)
		(property "Reference" "R766"
			(at 0 0 0)
			(layer "B.SilkS")
			(hide yes)
			(effects
				(font
					(size 1.27 1.27)
				)
				(justify mirror)
			)
		)
		(property "Value" ""
			(at 0 0 0)
			(layer "B.Fab")
			(effects
				(font
					(size 1.27 1.27)
				)
				(justify mirror)
			)
		)
		(duplicate_pad_numbers_are_jumpers no)
		(fp_line
			(start -0.7874 -0.4064)
			(end -0.7874 0.4064)
			(stroke
				(width 0.1524)
				(type default)
			)
			(layer "B.SilkS")
		)
		(fp_line
			(start -0.7874 0.4064)
			(end 0.7874 0.4064)
			(stroke
				(width 0.1524)
				(type default)
			)
			(layer "B.SilkS")
		)
		(fp_line
			(start 0.7874 -0.4064)
			(end -0.7874 -0.4064)
			(stroke
				(width 0.1524)
				(type default)
			)
			(layer "B.SilkS")
		)
		(fp_line
			(start 0.7874 0.4064)
			(end 0.7874 -0.4064)
			(stroke
				(width 0.1524)
				(type default)
			)
			(layer "B.SilkS")
		)
		(fp_line
			(start -0.67945 -0.3048)
			(end -0.67945 0.3048)
			(stroke
				(width 0.1)
				(type default)
			)
			(layer "B.Fab")
		)
		(fp_line
			(start -0.67945 0.3048)
			(end -0.120396 0.3048)
			(stroke
				(width 0.1)
				(type default)
			)
			(layer "B.Fab")
		)
		(fp_line
			(start -0.12065 -0.3048)
			(end -0.67945 -0.3048)
			(stroke
				(width 0.1)
				(type default)
			)
			(layer "B.Fab")
		)
		(fp_line
			(start -0.12065 -0.2794)
			(end -0.12065 -0.3048)
			(stroke
				(width 0.1)
				(type default)
			)
			(layer "B.Fab")
		)
		(fp_line
			(start -0.120396 0.2794)
			(end 0.12065 0.2794)
			(stroke
				(width 0.1)
				(type default)
			)
			(layer "B.Fab")
		)
		(fp_line
			(start -0.120396 0.3048)
			(end -0.120396 0.2794)
			(stroke
				(width 0.1)
				(type default)
			)
			(layer "B.Fab")
		)
		(fp_line
			(start 0.12065 -0.305054)
			(end 0.12065 -0.2794)
			(stroke
				(width 0.1)
				(type default)
			)
			(layer "B.Fab")
		)
		(fp_line
			(start 0.12065 -0.2794)
			(end -0.12065 -0.2794)
			(stroke
				(width 0.1)
				(type default)
			)
			(layer "B.Fab")
		)
		(fp_line
			(start 0.12065 0.2794)
			(end 0.12065 0.3048)
			(stroke
				(width 0.1)
				(type default)
			)
			(layer "B.Fab")
		)
		(fp_line
			(start 0.12065 0.3048)
			(end 0.67945 0.3048)
			(stroke
				(width 0.1)
				(type default)
			)
			(layer "B.Fab")
		)
		(fp_line
			(start 0.67945 -0.305054)
			(end 0.12065 -0.305054)
			(stroke
				(width 0.1)
				(type default)
			)
			(layer "B.Fab")
		)
		(fp_line
			(start 0.67945 0.3048)
			(end 0.67945 -0.305054)
			(stroke
				(width 0.1)
				(type default)
			)
			(layer "B.Fab")
		)
		(pad "1" smd circle
			(at 0.40005 0 180)
			(size 0 0)
			(layers "B.Cu" "B.Mask" "B.Paste")
			(net "P3V3_AUX")
		)
		(pad "2" smd circle
			(at -0.40005 0 180)
			(size 0 0)
			(layers "B.Cu" "B.Mask" "B.Paste")
			(net "JTAG_DBP_POWER_BTN_N")
		)
	)
	(footprint ""
		(layer "B.Cu")
		(at 226.652328 -403.769322 -90)
		(property "Reference" "PR3981"
			(at 0 0 90)
			(layer "B.SilkS")
			(hide yes)
			(effects
				(font
					(size 1.27 1.27)
				)
				(justify mirror)
			)
		)
		(property "Value" ""
			(at 0 0 90)
			(layer "B.Fab")
			(effects
				(font
					(size 1.27 1.27)
				)
				(justify mirror)
			)
		)
		(duplicate_pad_numbers_are_jumpers no)
		(fp_line
			(start -0.7874 0.4064)
			(end 0.7874 0.4064)
			(stroke
				(width 0.1524)
				(type default)
			)
			(layer "B.SilkS")
		)
		(fp_line
			(start 0.7874 0.4064)
			(end 0.7874 -0.4064)
			(stroke
				(width 0.1524)
				(type default)
			)
			(layer "B.SilkS")
		)
		(fp_line
			(start -0.7874 -0.4064)
			(end -0.7874 0.4064)
			(stroke
				(width 0.1524)
				(type default)
			)
			(layer "B.SilkS")
		)
		(fp_line
			(start 0.7874 -0.4064)
			(end -0.7874 -0.4064)
			(stroke
				(width 0.1524)
				(type default)
			)
			(layer "B.SilkS")
		)
		(fp_line
			(start -0.67945 0.3048)
			(end -0.120396 0.3048)
			(stroke
				(width 0.1)
				(type default)
			)
			(layer "B.Fab")
		)
		(fp_line
			(start -0.120396 0.3048)
			(end -0.120396 0.2794)
			(stroke
				(width 0.1)
				(type default)
			)
			(layer "B.Fab")
		)
		(fp_line
			(start 0.12065 0.3048)
			(end 0.67945 0.3048)
			(stroke
				(width 0.1)
				(type default)
			)
			(layer "B.Fab")
		)
		(fp_line
			(start 0.67945 0.3048)
			(end 0.67945 -0.305054)
			(stroke
				(width 0.1)
				(type default)
			)
			(layer "B.Fab")
		)
		(fp_line
			(start -0.120396 0.2794)
			(end 0.12065 0.2794)
			(stroke
				(width 0.1)
				(type default)
			)
			(layer "B.Fab")
		)
		(fp_line
			(start 0.12065 0.2794)
			(end 0.12065 0.3048)
			(stroke
				(width 0.1)
				(type default)
			)
			(layer "B.Fab")
		)
		(fp_line
			(start -0.12065 -0.2794)
			(end -0.12065 -0.3048)
			(stroke
				(width 0.1)
				(type default)
			)
			(layer "B.Fab")
		)
		(fp_line
			(start 0.12065 -0.2794)
			(end -0.12065 -0.2794)
			(stroke
				(width 0.1)
				(type default)
			)
			(layer "B.Fab")
		)
		(fp_line
			(start -0.67945 -0.3048)
			(end -0.67945 0.3048)
			(stroke
				(width 0.1)
				(type default)
			)
			(layer "B.Fab")
		)
		(fp_line
			(start -0.12065 -0.3048)
			(end -0.67945 -0.3048)
			(stroke
				(width 0.1)
				(type default)
			)
			(layer "B.Fab")
		)
		(fp_line
			(start 0.12065 -0.305054)
			(end 0.12065 -0.2794)
			(stroke
				(width 0.1)
				(type default)
			)
			(layer "B.Fab")
		)
		(fp_line
			(start 0.67945 -0.305054)
			(end 0.12065 -0.305054)
			(stroke
				(width 0.1)
				(type default)
			)
			(layer "B.Fab")
		)
		(pad "1" smd circle
			(at 0.40005 0 90)
			(size 0 0)
			(layers "B.Cu" "B.Mask" "B.Paste")
			(net "HSC_VDD_R_4")
		)
		(pad "2" smd circle
			(at -0.40005 0 90)
			(size 0 0)
			(layers "B.Cu" "B.Mask" "B.Paste")
			(net "HSC_VDD")
		)
	)
)
